FILE_TYPE=LIBRARY_PARTS;
primitive 'STANDOFF','STANDOFF_TH','STANDOFF_THLF';
  pin
    'PIN1':
      PIN_NUMBER='(1)';
  end_pin;
  body
    PART_NAME='STANDOFF';
    PHYS_DES_PREFIX='RM';
 end_body;
end_primitive;


primitive 'STANDOFF_TH1','STANDOFF_TH2','STANDOFF_TH3';
  pin
    'IO1':
      PIN_NUMBER='(1)';
      BIDIRECTIONAL='TRUE';
      INPUT_LOAD='(-0.01,0.01)';
      OUTPUT_LOAD='(1.0,-1.0)';
  end_pin;
  body
    PART_NAME='STANDOFF';
    PHYS_DES_PREFIX='RM';
 end_body;
end_primitive;

END.
